(kicad_pcb
	(version 20241229)
	(generator "pcbnew")
	(generator_version "9.0")
	(general
		(thickness 1.258)
		(legacy_teardrops no)
	)
	(paper "A4")
	(title_block
		(date "2024-05-27")
		(rev "1.1.2")
		(comment 9 "footprints 2-7 of 64")
	)
	(layers
		(0 "F.Cu" signal)
		(4 "In1.Cu" power)
		(6 "In2.Cu" power)
		(8 "In3.Cu" signal)
		(10 "In4.Cu" signal)
		(2 "B.Cu" signal)
		(9 "F.Adhes" user "F.Adhesive")
		(11 "B.Adhes" user "B.Adhesive")
		(13 "F.Paste" user)
		(15 "B.Paste" user)
		(5 "F.SilkS" user "F.Silkscreen")
		(7 "B.SilkS" user "B.Silkscreen")
		(1 "F.Mask" user)
		(3 "B.Mask" user)
		(17 "Dwgs.User" user "User.Drawings")
		(19 "Cmts.User" user "User.Comments")
		(21 "Eco1.User" user "User.Eco1")
		(23 "Eco2.User" user "User.Eco2")
		(25 "Edge.Cuts" user)
		(27 "Margin" user)
		(31 "F.CrtYd" user "F.Courtyard")
		(29 "B.CrtYd" user "B.Courtyard")
		(35 "F.Fab" user)
		(33 "B.Fab" user)
	)
	(footprint "antmicro-footprints:oshw-logo"
		(layer "F.Cu")
		(at 161.775 74.25)
		(descr "OSHW Logo")
		(tags "OSHW Logo")
		(property "Reference" "N2"
			(at 0 -4.4 0)
			(layer "F.SilkS")
			(hide yes)
			(effects
				(font
					(size 0.7 0.7)
					(thickness 0.15)
				)
				(justify left bottom)
			)
		)
		(property "Value" "oshw_logo"
			(at 0 -3.4 0)
			(layer "F.Fab")
			(hide yes)
			(effects
				(font
					(size 0.7 0.7)
					(thickness 0.15)
				)
				(justify left bottom)
			)
		)
		(property "Author" "Antmicro"
			(at 0 0 0)
			(layer "F.Fab")
			(hide yes)
			(effects
				(font
					(size 1 1)
					(thickness 0.15)
				)
			)
		)
		(property "License" "Apache-2.0"
			(at 0 0 0)
			(layer "F.Fab")
			(hide yes)
			(effects
				(font
					(size 1 1)
					(thickness 0.15)
				)
			)
		)
		(property "MPN" ""
			(at 0 0 0)
			(layer "F.Fab")
			(hide yes)
			(effects
				(font
					(size 1 1)
					(thickness 0.15)
				)
			)
		)
		(property "Manufacturer" ""
			(at 0 0 0)
			(layer "F.Fab")
			(hide yes)
			(effects
				(font
					(size 1 1)
					(thickness 0.15)
				)
			)
		)
		(sheetfile "ddr5-testbed.kicad_sch")
		(attr exclude_from_pos_files allow_soldermask_bridges)
	)
	(footprint "antmicro-footprints:C_0402_1005Metric"
		(layer "F.Cu")
		(at 134.175 85.2 90)
		(descr "Capacitor SMD 0402")
		(tags "capacitor SMD 0402")
		(property "Reference" "C34"
			(at -1.08 1.285 90)
			(layer "F.SilkS")
			(effects
				(font
					(size 0.7 0.7)
					(thickness 0.15)
				)
				(justify left bottom)
			)
		)
		(property "Value" "C_4u7_0402"
			(at 0 1.4 90)
			(layer "F.Fab")
			(hide yes)
			(effects
				(font
					(size 0.7 0.7)
					(thickness 0.15)
				)
				(justify left bottom)
			)
		)
		(property "Description" " "
			(at 0 0 90)
			(layer "F.Fab")
			(hide yes)
			(effects
				(font
					(size 1.27 1.27)
					(thickness 0.15)
				)
			)
		)
		(property "Author" "Antmicro"
			(at 219.375 -48.975 0)
			(layer "F.Fab")
			(hide yes)
			(effects
				(font
					(size 1 1)
					(thickness 0.15)
				)
			)
		)
		(property "Dielectric" ""
			(at 219.375 -48.975 0)
			(layer "F.Fab")
			(hide yes)
			(effects
				(font
					(size 1 1)
					(thickness 0.15)
				)
			)
		)
		(property "License" "Apache-2.0"
			(at 219.375 -48.975 0)
			(layer "F.Fab")
			(hide yes)
			(effects
				(font
					(size 1 1)
					(thickness 0.15)
				)
			)
		)
		(property "MPN" "GRM155R61A475MEAAD"
			(at 219.375 -48.975 0)
			(layer "F.Fab")
			(hide yes)
			(effects
				(font
					(size 1 1)
					(thickness 0.15)
				)
			)
		)
		(property "Manufacturer" "Murata"
			(at 219.375 -48.975 0)
			(layer "F.Fab")
			(hide yes)
			(effects
				(font
					(size 1 1)
					(thickness 0.15)
				)
			)
		)
		(property "Val" "4u7"
			(at 219.375 -48.975 0)
			(layer "F.Fab")
			(hide yes)
			(effects
				(font
					(size 1 1)
					(thickness 0.15)
				)
			)
		)
		(property "Voltage" ""
			(at 219.375 -48.975 0)
			(layer "F.Fab")
			(hide yes)
			(effects
				(font
					(size 1 1)
					(thickness 0.15)
				)
			)
		)
		(sheetname "EEPROM")
		(sheetfile "EEPROM.kicad_sch")
		(attr smd)
		(fp_rect
			(start -0.925 -0.47)
			(end 0.925 0.47)
			(stroke
				(width 0.05)
				(type default)
			)
			(fill no)
			(layer "F.CrtYd")
		)
		(fp_line
			(start 0.504 -0.25)
			(end 0.504 0.248)
			(stroke
				(width 0.15)
				(type solid)
			)
			(layer "F.Fab")
		)
		(fp_line
			(start -0.494 -0.25)
			(end 0.504 -0.25)
			(stroke
				(width 0.15)
				(type solid)
			)
			(layer "F.Fab")
		)
		(fp_line
			(start 0.504 0.248)
			(end -0.494 0.248)
			(stroke
				(width 0.15)
				(type solid)
			)
			(layer "F.Fab")
		)
		(fp_line
			(start -0.494 0.248)
			(end -0.494 -0.25)
			(stroke
				(width 0.15)
				(type solid)
			)
			(layer "F.Fab")
		)
		(pad "1" smd roundrect
			(at -0.48 0 90)
			(size 0.59 0.64)
			(layers "F.Cu" "F.Mask" "F.Paste")
			(roundrect_rratio 0.25)
			(net 50 "1V8_SYS")
			(pintype "passive")
		)
		(pad "2" smd roundrect
			(at 0.48 0 90)
			(size 0.59 0.64)
			(layers "F.Cu" "F.Mask" "F.Paste")
			(roundrect_rratio 0.25)
			(net 1 "GND")
			(pintype "passive")
		)
	)
	(footprint "antmicro-footprints:C_0402_1005Metric"
		(layer "F.Cu")
		(at 130.66 81.15)
		(descr "Capacitor SMD 0402")
		(tags "capacitor SMD 0402")
		(property "Reference" "C37"
			(at -1.05 -0.57 0)
			(layer "F.SilkS")
			(effects
				(font
					(size 0.7 0.7)
					(thickness 0.15)
				)
				(justify left bottom)
			)
		)
		(property "Value" "C_4u7_0402"
			(at 0 1.4 0)
			(layer "F.Fab")
			(hide yes)
			(effects
				(font
					(size 0.7 0.7)
					(thickness 0.15)
				)
				(justify left bottom)
			)
		)
		(property "Description" " "
			(at 0 0 0)
			(layer "F.Fab")
			(hide yes)
			(effects
				(font
					(size 1.27 1.27)
					(thickness 0.15)
				)
			)
		)
		(property "Author" "Antmicro"
			(at 0 0 0)
			(layer "F.Fab")
			(hide yes)
			(effects
				(font
					(size 1 1)
					(thickness 0.15)
				)
			)
		)
		(property "Dielectric" ""
			(at 0 0 0)
			(layer "F.Fab")
			(hide yes)
			(effects
				(font
					(size 1 1)
					(thickness 0.15)
				)
			)
		)
		(property "License" "Apache-2.0"
			(at 0 0 0)
			(layer "F.Fab")
			(hide yes)
			(effects
				(font
					(size 1 1)
					(thickness 0.15)
				)
			)
		)
		(property "MPN" "GRM155R61A475MEAAD"
			(at 0 0 0)
			(layer "F.Fab")
			(hide yes)
			(effects
				(font
					(size 1 1)
					(thickness 0.15)
				)
			)
		)
		(property "Manufacturer" "Murata"
			(at 0 0 0)
			(layer "F.Fab")
			(hide yes)
			(effects
				(font
					(size 1 1)
					(thickness 0.15)
				)
			)
		)
		(property "Val" "4u7"
			(at 0 0 0)
			(layer "F.Fab")
			(hide yes)
			(effects
				(font
					(size 1 1)
					(thickness 0.15)
				)
			)
		)
		(property "Voltage" ""
			(at 0 0 0)
			(layer "F.Fab")
			(hide yes)
			(effects
				(font
					(size 1 1)
					(thickness 0.15)
				)
			)
		)
		(sheetname "EEPROM")
		(sheetfile "EEPROM.kicad_sch")
		(attr smd)
		(fp_rect
			(start -0.925 -0.47)
			(end 0.925 0.47)
			(stroke
				(width 0.05)
				(type default)
			)
			(fill no)
			(layer "F.CrtYd")
		)
		(fp_line
			(start -0.494 -0.25)
			(end 0.504 -0.25)
			(stroke
				(width 0.15)
				(type solid)
			)
			(layer "F.Fab")
		)
		(fp_line
			(start -0.494 0.248)
			(end -0.494 -0.25)
			(stroke
				(width 0.15)
				(type solid)
			)
			(layer "F.Fab")
		)
		(fp_line
			(start 0.504 -0.25)
			(end 0.504 0.248)
			(stroke
				(width 0.15)
				(type solid)
			)
			(layer "F.Fab")
		)
		(fp_line
			(start 0.504 0.248)
			(end -0.494 0.248)
			(stroke
				(width 0.15)
				(type solid)
			)
			(layer "F.Fab")
		)
		(pad "1" smd roundrect
			(at -0.48 0)
			(size 0.59 0.64)
			(layers "F.Cu" "F.Mask" "F.Paste")
			(roundrect_rratio 0.25)
			(net 52 "/EEPROM/VDD_LED")
			(pintype "passive")
		)
		(pad "2" smd roundrect
			(at 0.48 0)
			(size 0.59 0.64)
			(layers "F.Cu" "F.Mask" "F.Paste")
			(roundrect_rratio 0.25)
			(net 1 "GND")
			(pintype "passive")
		)
	)
	(footprint "antmicro-footprints:C_0402_1005Metric"
		(layer "F.Cu")
		(at 122.76 81.545)
		(descr "Capacitor SMD 0402")
		(tags "capacitor SMD 0402")
		(property "Reference" "C38"
			(at 0.92 0.345 0)
			(layer "F.SilkS")
			(effects
				(font
					(size 0.7 0.7)
					(thickness 0.15)
				)
				(justify left bottom)
			)
		)
		(property "Value" "C_100n_0402"
			(at 0 1.4 0)
			(layer "F.Fab")
			(hide yes)
			(effects
				(font
					(size 0.7 0.7)
					(thickness 0.15)
				)
				(justify left bottom)
			)
		)
		(property "Description" " "
			(at 0 0 0)
			(layer "F.Fab")
			(hide yes)
			(effects
				(font
					(size 1.27 1.27)
					(thickness 0.15)
				)
			)
		)
		(property "Author" "Antmicro"
			(at 0 0 0)
			(layer "F.Fab")
			(hide yes)
			(effects
				(font
					(size 1 1)
					(thickness 0.15)
				)
			)
		)
		(property "Dielectric" "X5R"
			(at 0 0 0)
			(layer "F.Fab")
			(hide yes)
			(effects
				(font
					(size 1 1)
					(thickness 0.15)
				)
			)
		)
		(property "License" "Apache-2.0"
			(at 0 0 0)
			(layer "F.Fab")
			(hide yes)
			(effects
				(font
					(size 1 1)
					(thickness 0.15)
				)
			)
		)
		(property "MPN" "GRM155R61H104KE14D"
			(at 0 0 0)
			(layer "F.Fab")
			(hide yes)
			(effects
				(font
					(size 1 1)
					(thickness 0.15)
				)
			)
		)
		(property "Manufacturer" "Murata"
			(at 0 0 0)
			(layer "F.Fab")
			(hide yes)
			(effects
				(font
					(size 1 1)
					(thickness 0.15)
				)
			)
		)
		(property "Val" "100n"
			(at 0 0 0)
			(layer "F.Fab")
			(hide yes)
			(effects
				(font
					(size 1 1)
					(thickness 0.15)
				)
			)
		)
		(property "Voltage" "50V"
			(at 0 0 0)
			(layer "F.Fab")
			(hide yes)
			(effects
				(font
					(size 1 1)
					(thickness 0.15)
				)
			)
		)
		(sheetname "EEPROM")
		(sheetfile "EEPROM.kicad_sch")
		(attr smd)
		(fp_rect
			(start -0.925 -0.47)
			(end 0.925 0.47)
			(stroke
				(width 0.05)
				(type default)
			)
			(fill no)
			(layer "F.CrtYd")
		)
		(fp_line
			(start -0.494 -0.25)
			(end 0.504 -0.25)
			(stroke
				(width 0.15)
				(type solid)
			)
			(layer "F.Fab")
		)
		(fp_line
			(start -0.494 0.248)
			(end -0.494 -0.25)
			(stroke
				(width 0.15)
				(type solid)
			)
			(layer "F.Fab")
		)
		(fp_line
			(start 0.504 -0.25)
			(end 0.504 0.248)
			(stroke
				(width 0.15)
				(type solid)
			)
			(layer "F.Fab")
		)
		(fp_line
			(start 0.504 0.248)
			(end -0.494 0.248)
			(stroke
				(width 0.15)
				(type solid)
			)
			(layer "F.Fab")
		)
		(pad "1" smd roundrect
			(at -0.48 0)
			(size 0.59 0.64)
			(layers "F.Cu" "F.Mask" "F.Paste")
			(roundrect_rratio 0.25)
			(net 50 "1V8_SYS")
			(pintype "passive")
		)
		(pad "2" smd roundrect
			(at 0.48 0)
			(size 0.59 0.64)
			(layers "F.Cu" "F.Mask" "F.Paste")
			(roundrect_rratio 0.25)
			(net 1 "GND")
			(pintype "passive")
		)
	)
	(footprint "antmicro-footprints:LED_0603_1608Metric_G"
		(layer "F.Cu")
		(at 131.075 72.9 90)
		(descr "LED SMD 0603 Green")
		(tags "LED SMD 0603 Green")
		(property "Reference" "D4"
			(at 1.53 -0.775 180)
			(layer "F.SilkS")
			(effects
				(font
					(size 0.7 0.7)
					(thickness 0.15)
				)
				(justify left bottom)
			)
		)
		(property "Value" "LED_G_0603_KP-1608CGCK"
			(at 0 1.6 90)
			(layer "F.Fab")
			(hide yes)
			(effects
				(font
					(size 0.7 0.7)
					(thickness 0.15)
				)
				(justify left bottom)
			)
		)
		(property "Author" "Antmicro"
			(at 203.975 -58.175 0)
			(layer "F.Fab")
			(hide yes)
			(effects
				(font
					(size 1 1)
					(thickness 0.15)
				)
			)
		)
		(property "License" "Apache-2.0"
			(at 203.975 -58.175 0)
			(layer "F.Fab")
			(hide yes)
			(effects
				(font
					(size 1 1)
					(thickness 0.15)
				)
			)
		)
		(property "MPN" "KP-1608CGCK"
			(at 203.975 -58.175 0)
			(layer "F.Fab")
			(hide yes)
			(effects
				(font
					(size 1 1)
					(thickness 0.15)
				)
			)
		)
		(property "Manufacturer" "Kingbright"
			(at 203.975 -58.175 0)
			(layer "F.Fab")
			(hide yes)
			(effects
				(font
					(size 1 1)
					(thickness 0.15)
				)
			)
		)
		(sheetname "EEPROM")
		(sheetfile "EEPROM.kicad_sch")
		(attr smd)
		(fp_line
			(start 0.22 -0.35)
			(end -0.22 -0.35)
			(stroke
				(width 0.15)
				(type solid)
			)
			(layer "F.SilkS")
		)
		(fp_line
			(start -1.18 -0.319)
			(end -1.18 0.321)
			(stroke
				(width 0.15)
				(type solid)
			)
			(layer "F.SilkS")
		)
		(fp_line
			(start 0.105328 0.001008)
			(end 0.24 0.001)
			(stroke
				(width 0.1)
				(type solid)
			)
			(layer "F.SilkS")
		)
		(fp_line
			(start -0.094672 0.001008)
			(end 0.105328 -0.198992)
			(stroke
				(width 0.1)
				(type solid)
			)
			(layer "F.SilkS")
		)
		(fp_line
			(start -0.094672 0.001008)
			(end -0.24 0.001008)
			(stroke
				(width 0.1)
				(type solid)
			)
			(layer "F.SilkS")
		)
		(fp_line
			(start 0.105328 0.201008)
			(end 0.105328 -0.198992)
			(stroke
				(width 0.1)
				(type solid)
			)
			(layer "F.SilkS")
		)
		(fp_line
			(start 0.105328 0.201008)
			(end -0.094672 0.001008)
			(stroke
				(width 0.1)
				(type solid)
			)
			(layer "F.SilkS")
		)
		(fp_line
			(start -0.094672 0.201008)
			(end -0.094672 -0.198992)
			(stroke
				(width 0.1)
				(type solid)
			)
			(layer "F.SilkS")
		)
		(fp_line
			(start 0.22 0.35)
			(end -0.22 0.35)
			(stroke
				(width 0.15)
				(type solid)
			)
			(layer "F.SilkS")
		)
		(fp_rect
			(start 1.25 0.65)
			(end -1.25 -0.65)
			(stroke
				(width 0.05)
				(type solid)
			)
			(fill no)
			(layer "F.CrtYd")
		)
		(fp_line
			(start 0.201 -0.202)
			(end -0.101 0)
			(stroke
				(width 0.15)
				(type solid)
			)
			(layer "F.Fab")
		)
		(fp_line
			(start -0.199 -0.202)
			(end -0.199 0.1)
			(stroke
				(width 0.15)
				(type solid)
			)
			(layer "F.Fab")
		)
		(fp_line
			(start 0.599 0)
			(end 0.201 0)
			(stroke
				(width 0.15)
				(type solid)
			)
			(layer "F.Fab")
		)
		(fp_line
			(start 0.201 0)
			(end 0.201 -0.202)
			(stroke
				(width 0.15)
				(type solid)
			)
			(layer "F.Fab")
		)
		(fp_line
			(start -0.101 0)
			(end 0.201 0.2)
			(stroke
				(width 0.15)
				(type solid)
			)
			(layer "F.Fab")
		)
		(fp_line
			(start -0.199 0)
			(end -0.597 0)
			(stroke
				(width 0.15)
				(type solid)
			)
			(layer "F.Fab")
		)
		(fp_line
			(start 0.201 0.2)
			(end 0.201 0)
			(stroke
				(width 0.15)
				(type solid)
			)
			(layer "F.Fab")
		)
		(fp_line
			(start -0.199 0.2)
			(end -0.199 0.1)
			(stroke
				(width 0.15)
				(type solid)
			)
			(layer "F.Fab")
		)
		(fp_rect
			(start 0.848 0.4)
			(end -0.85 -0.402)
			(stroke
				(width 0.15)
				(type solid)
			)
			(fill no)
			(layer "F.Fab")
		)
		(pad "1" smd roundrect
			(at -0.7 0 270)
			(size 0.8 1)
			(layers "F.Cu" "F.Mask" "F.Paste")
			(roundrect_rratio 0.2)
			(net 7 "Net-(D4-Pad1)")
			(pinfunction "1")
			(pintype "passive")
		)
		(pad "2" smd roundrect
			(at 0.7 0 270)
			(size 0.8 1)
			(layers "F.Cu" "F.Mask" "F.Paste")
			(roundrect_rratio 0.2)
			(net 1 "GND")
			(pinfunction "2")
			(pintype "passive")
		)
	)
	(footprint "antmicro-footprints:LED_0603_1608Metric_G"
		(layer "F.Cu")
		(at 129.258332 72.9 90)
		(descr "LED SMD 0603 Green")
		(tags "LED SMD 0603 Green")
		(property "Reference" "D3"
			(at 1.53 -0.688332 180)
			(layer "F.SilkS")
			(effects
				(font
					(size 0.7 0.7)
					(thickness 0.15)
				)
				(justify left bottom)
			)
		)
		(property "Value" "LED_G_0603_KP-1608CGCK"
			(at 0 1.6 90)
			(layer "F.Fab")
			(hide yes)
			(effects
				(font
					(size 0.7 0.7)
					(thickness 0.15)
				)
				(justify left bottom)
			)
		)
		(property "Author" "Antmicro"
			(at 202.158332 -56.358332 0)
			(layer "F.Fab")
			(hide yes)
			(effects
				(font
					(size 1 1)
					(thickness 0.15)
				)
			)
		)
		(property "License" "Apache-2.0"
			(at 202.158332 -56.358332 0)
			(layer "F.Fab")
			(hide yes)
			(effects
				(font
					(size 1 1)
					(thickness 0.15)
				)
			)
		)
		(property "MPN" "KP-1608CGCK"
			(at 202.158332 -56.358332 0)
			(layer "F.Fab")
			(hide yes)
			(effects
				(font
					(size 1 1)
					(thickness 0.15)
				)
			)
		)
		(property "Manufacturer" "Kingbright"
			(at 202.158332 -56.358332 0)
			(layer "F.Fab")
			(hide yes)
			(effects
				(font
					(size 1 1)
					(thickness 0.15)
				)
			)
		)
		(sheetname "EEPROM")
		(sheetfile "EEPROM.kicad_sch")
		(attr smd)
		(fp_line
			(start 0.22 -0.35)
			(end -0.22 -0.35)
			(stroke
				(width 0.15)
				(type solid)
			)
			(layer "F.SilkS")
		)
		(fp_line
			(start -1.18 -0.319)
			(end -1.18 0.321)
			(stroke
				(width 0.15)
				(type solid)
			)
			(layer "F.SilkS")
		)
		(fp_line
			(start 0.105328 0.001008)
			(end 0.24 0.001)
			(stroke
				(width 0.1)
				(type solid)
			)
			(layer "F.SilkS")
		)
		(fp_line
			(start -0.094672 0.001008)
			(end 0.105328 -0.198992)
			(stroke
				(width 0.1)
				(type solid)
			)
			(layer "F.SilkS")
		)
		(fp_line
			(start -0.094672 0.001008)
			(end -0.24 0.001008)
			(stroke
				(width 0.1)
				(type solid)
			)
			(layer "F.SilkS")
		)
		(fp_line
			(start 0.105328 0.201008)
			(end 0.105328 -0.198992)
			(stroke
				(width 0.1)
				(type solid)
			)
			(layer "F.SilkS")
		)
		(fp_line
			(start 0.105328 0.201008)
			(end -0.094672 0.001008)
			(stroke
				(width 0.1)
				(type solid)
			)
			(layer "F.SilkS")
		)
		(fp_line
			(start -0.094672 0.201008)
			(end -0.094672 -0.198992)
			(stroke
				(width 0.1)
				(type solid)
			)
			(layer "F.SilkS")
		)
		(fp_line
			(start 0.22 0.35)
			(end -0.22 0.35)
			(stroke
				(width 0.15)
				(type solid)
			)
			(layer "F.SilkS")
		)
		(fp_rect
			(start 1.25 0.65)
			(end -1.25 -0.65)
			(stroke
				(width 0.05)
				(type solid)
			)
			(fill no)
			(layer "F.CrtYd")
		)
		(fp_line
			(start 0.201 -0.202)
			(end -0.101 0)
			(stroke
				(width 0.15)
				(type solid)
			)
			(layer "F.Fab")
		)
		(fp_line
			(start -0.199 -0.202)
			(end -0.199 0.1)
			(stroke
				(width 0.15)
				(type solid)
			)
			(layer "F.Fab")
		)
		(fp_line
			(start 0.599 0)
			(end 0.201 0)
			(stroke
				(width 0.15)
				(type solid)
			)
			(layer "F.Fab")
		)
		(fp_line
			(start 0.201 0)
			(end 0.201 -0.202)
			(stroke
				(width 0.15)
				(type solid)
			)
			(layer "F.Fab")
		)
		(fp_line
			(start -0.101 0)
			(end 0.201 0.2)
			(stroke
				(width 0.15)
				(type solid)
			)
			(layer "F.Fab")
		)
		(fp_line
			(start -0.199 0)
			(end -0.597 0)
			(stroke
				(width 0.15)
				(type solid)
			)
			(layer "F.Fab")
		)
		(fp_line
			(start 0.201 0.2)
			(end 0.201 0)
			(stroke
				(width 0.15)
				(type solid)
			)
			(layer "F.Fab")
		)
		(fp_line
			(start -0.199 0.2)
			(end -0.199 0.1)
			(stroke
				(width 0.15)
				(type solid)
			)
			(layer "F.Fab")
		)
		(fp_rect
			(start 0.848 0.4)
			(end -0.85 -0.402)
			(stroke
				(width 0.15)
				(type solid)
			)
			(fill no)
			(layer "F.Fab")
		)
		(pad "1" smd roundrect
			(at -0.7 0 270)
			(size 0.8 1)
			(layers "F.Cu" "F.Mask" "F.Paste")
			(roundrect_rratio 0.2)
			(net 6 "Net-(D3-Pad1)")
			(pinfunction "1")
			(pintype "passive")
		)
		(pad "2" smd roundrect
			(at 0.7 0 270)
			(size 0.8 1)
			(layers "F.Cu" "F.Mask" "F.Paste")
			(roundrect_rratio 0.2)
			(net 1 "GND")
			(pinfunction "2")
			(pintype "passive")
		)
	)
)
